# T6G (Grand Teton) — schematic netlist excerpt (pin names and nets, part order shuffled) for the footprints in the layout excerpt that follows; sources: Cadence DE-HDL packaged netlist, KiCad conversion of 04192023_DAF0TMB3IC0_F0TG_MB_C_brd_V02_OCP.brd

C98  Q_CAP  0.1UF 25V 10% X7R  pkg 0402  page 183 : A = P3V3_9ZXL045_P1_VDD ; B = GND
C225  Q_CAP  100UF 4V 20% X6S  pkg C0805  page 323 : A = P0V9_CPU1_RT0_2A ; B = GND
C2575  Q_CAP  22UF 4V 20% X6S  pkg C0402  page 70 : A = PVDDCR_SOC_P0 ; B = GND

(kicad_pcb
	(version 20260206)
	(generator "pcbnew")
	(generator_version "10.0")
	(general
		(thickness 1.6)
		(legacy_teardrops no)
	)
	(paper "A4")
	(title_block
		(title "04192023_DAF0TMB3IC0_F0TG_MB_C_brd_V02_OCP.brd")
		(comment 1 "Grand Teton / footprints 6794-6796 of 8354")
	)
	(layers
		(0 "F.Cu" signal "TOP")
		(4 "In1.Cu" signal "GND")
		(6 "In2.Cu" signal "IN1")
		(8 "In3.Cu" signal "GND1")
		(10 "In4.Cu" signal "IN2")
		(12 "In5.Cu" signal "GND2")
		(14 "In6.Cu" signal "IN3")
		(16 "In7.Cu" signal "GND3")
		(18 "In8.Cu" signal "VCC")
		(20 "In9.Cu" signal "VCC1")
		(22 "In10.Cu" signal "GND4")
		(24 "In11.Cu" signal "IN4")
		(26 "In12.Cu" signal "GND5")
		(28 "In13.Cu" signal "IN5")
		(30 "In14.Cu" signal "GND6")
		(32 "In15.Cu" signal "IN6")
		(34 "In16.Cu" signal "GND7")
		(2 "B.Cu" signal "BOTTOM")
		(9 "F.Adhes" user "F.Adhesive")
		(11 "B.Adhes" user "B.Adhesive")
		(13 "F.Paste" user "Package Geometry/Pastemask Top")
		(15 "B.Paste" user "Package Geometry/Pastemask Bottom")
		(5 "F.SilkS" user "Ref Des/Silkscreen Top")
		(7 "B.SilkS" user "Ref Des/Silkscreen Bottom")
		(1 "F.Mask" user "Board Geometry/Soldermask Top")
		(3 "B.Mask" user "Board Geometry/Soldermask Bottom")
		(17 "Dwgs.User" user "User.Drawings")
		(19 "Cmts.User" user "User.Comments")
		(21 "Eco1.User" user "User.Eco1")
		(23 "Eco2.User" user "User.Eco2")
		(25 "Edge.Cuts" user "Board Geometry/Outline")
		(27 "Margin" user)
		(31 "F.CrtYd" user "Package Geometry/Place Bound Top")
		(29 "B.CrtYd" user "Package Geometry/Place Bound Bottom")
		(35 "F.Fab" user "Ref Des/Assembly Top")
		(33 "B.Fab" user "Ref Des/Assembly Bottom")
	)
	(footprint ""
		(layer "B.Cu")
		(at 351.739454 -255.84531 180)
		(property "Reference" "C2575"
			(at 0 0 0)
			(layer "B.SilkS")
			(hide yes)
			(effects
				(font
					(size 1.27 1.27)
				)
				(justify mirror)
			)
		)
		(property "Value" ""
			(at 0 0 0)
			(layer "B.Fab")
			(effects
				(font
					(size 1.27 1.27)
				)
				(justify mirror)
			)
		)
		(duplicate_pad_numbers_are_jumpers no)
		(fp_line
			(start 0.7874 0.4064)
			(end 0.7874 -0.4064)
			(stroke
				(width 0.1524)
				(type default)
			)
			(layer "B.SilkS")
		)
		(fp_line
			(start 0.7874 -0.4064)
			(end -0.7874 -0.4064)
			(stroke
				(width 0.1524)
				(type default)
			)
			(layer "B.SilkS")
		)
		(fp_line
			(start -0.7874 0.4064)
			(end 0.7874 0.4064)
			(stroke
				(width 0.1524)
				(type default)
			)
			(layer "B.SilkS")
		)
		(fp_line
			(start -0.7874 -0.4064)
			(end -0.7874 0.4064)
			(stroke
				(width 0.1524)
				(type default)
			)
			(layer "B.SilkS")
		)
		(fp_line
			(start 0.67945 0.3048)
			(end 0.67945 -0.305054)
			(stroke
				(width 0.1)
				(type default)
			)
			(layer "B.Fab")
		)
		(fp_line
			(start 0.67945 -0.305054)
			(end 0.12065 -0.305054)
			(stroke
				(width 0.1)
				(type default)
			)
			(layer "B.Fab")
		)
		(fp_line
			(start 0.12065 0.3048)
			(end 0.67945 0.3048)
			(stroke
				(width 0.1)
				(type default)
			)
			(layer "B.Fab")
		)
		(fp_line
			(start 0.12065 0.2794)
			(end 0.12065 0.3048)
			(stroke
				(width 0.1)
				(type default)
			)
			(layer "B.Fab")
		)
		(fp_line
			(start 0.12065 -0.2794)
			(end -0.12065 -0.2794)
			(stroke
				(width 0.1)
				(type default)
			)
			(layer "B.Fab")
		)
		(fp_line
			(start 0.12065 -0.305054)
			(end 0.12065 -0.2794)
			(stroke
				(width 0.1)
				(type default)
			)
			(layer "B.Fab")
		)
		(fp_line
			(start -0.120396 0.3048)
			(end -0.120396 0.2794)
			(stroke
				(width 0.1)
				(type default)
			)
			(layer "B.Fab")
		)
		(fp_line
			(start -0.120396 0.2794)
			(end 0.12065 0.2794)
			(stroke
				(width 0.1)
				(type default)
			)
			(layer "B.Fab")
		)
		(fp_line
			(start -0.12065 -0.2794)
			(end -0.12065 -0.3048)
			(stroke
				(width 0.1)
				(type default)
			)
			(layer "B.Fab")
		)
		(fp_line
			(start -0.12065 -0.3048)
			(end -0.67945 -0.3048)
			(stroke
				(width 0.1)
				(type default)
			)
			(layer "B.Fab")
		)
		(fp_line
			(start -0.67945 0.3048)
			(end -0.120396 0.3048)
			(stroke
				(width 0.1)
				(type default)
			)
			(layer "B.Fab")
		)
		(fp_line
			(start -0.67945 -0.3048)
			(end -0.67945 0.3048)
			(stroke
				(width 0.1)
				(type default)
			)
			(layer "B.Fab")
		)
		(pad "1" smd circle
			(at 0.40005 0)
			(size 0 0)
			(layers "B.Cu" "B.Mask" "B.Paste")
			(net "PVDDCR_SOC_P0")
		)
		(pad "2" smd circle
			(at -0.40005 0)
			(size 0 0)
			(layers "B.Cu" "B.Mask" "B.Paste")
			(net "GND")
		)
	)
	(footprint ""
		(layer "B.Cu")
		(at 69.861684 -390.073134 180)
		(property "Reference" "C225"
			(at 0 0 0)
			(layer "B.SilkS")
			(hide yes)
			(effects
				(font
					(size 1.27 1.27)
				)
				(justify mirror)
			)
		)
		(property "Value" ""
			(at 0 0 0)
			(layer "B.Fab")
			(effects
				(font
					(size 1.27 1.27)
				)
				(justify mirror)
			)
		)
		(duplicate_pad_numbers_are_jumpers no)
		(fp_line
			(start 1.524 0.762)
			(end 1.524 -0.762)
			(stroke
				(width 0.1524)
				(type default)
			)
			(layer "B.SilkS")
		)
		(fp_line
			(start 1.524 -0.762)
			(end -1.524 -0.762)
			(stroke
				(width 0.1524)
				(type default)
			)
			(layer "B.SilkS")
		)
		(fp_line
			(start -1.524 0.762)
			(end 1.524 0.762)
			(stroke
				(width 0.1524)
				(type default)
			)
			(layer "B.SilkS")
		)
		(fp_line
			(start -1.524 -0.762)
			(end -1.524 0.762)
			(stroke
				(width 0.1524)
				(type default)
			)
			(layer "B.SilkS")
		)
		(fp_line
			(start 1.1049 0.724916)
			(end -1.1049 0.724916)
			(stroke
				(width 0.1)
				(type default)
			)
			(layer "B.Fab")
		)
		(fp_line
			(start 1.1049 -0.724916)
			(end 1.1049 0.724916)
			(stroke
				(width 0.1)
				(type default)
			)
			(layer "B.Fab")
		)
		(fp_line
			(start -1.1049 0.724916)
			(end -1.1049 -0.724916)
			(stroke
				(width 0.1)
				(type default)
			)
			(layer "B.Fab")
		)
		(fp_line
			(start -1.1049 -0.724916)
			(end 1.1049 -0.724916)
			(stroke
				(width 0.1)
				(type default)
			)
			(layer "B.Fab")
		)
		(pad "1" smd rect
			(at 0.889 0 180)
			(size 1.016 1.27)
			(layers "B.Cu" "B.Mask" "B.Paste")
			(net "P0V9_CPU1_RT0_2A")
		)
		(pad "2" smd rect
			(at -0.889 0 180)
			(size 1.016 1.27)
			(layers "B.Cu" "B.Mask" "B.Paste")
			(net "GND")
		)
	)
	(footprint ""
		(layer "B.Cu")
		(at 104.521762 -410.3116 180)
		(property "Reference" "C98"
			(at 0 0 0)
			(layer "B.SilkS")
			(hide yes)
			(effects
				(font
					(size 1.27 1.27)
				)
				(justify mirror)
			)
		)
		(property "Value" ""
			(at 0 0 0)
			(layer "B.Fab")
			(effects
				(font
					(size 1.27 1.27)
				)
				(justify mirror)
			)
		)
		(duplicate_pad_numbers_are_jumpers no)
		(fp_line
			(start 0.7874 0.4064)
			(end 0.7874 -0.4064)
			(stroke
				(width 0.1524)
				(type default)
			)
			(layer "B.SilkS")
		)
		(fp_line
			(start 0.7874 -0.4064)
			(end -0.7874 -0.4064)
			(stroke
				(width 0.1524)
				(type default)
			)
			(layer "B.SilkS")
		)
		(fp_line
			(start -0.7874 0.4064)
			(end 0.7874 0.4064)
			(stroke
				(width 0.1524)
				(type default)
			)
			(layer "B.SilkS")
		)
		(fp_line
			(start -0.7874 -0.4064)
			(end -0.7874 0.4064)
			(stroke
				(width 0.1524)
				(type default)
			)
			(layer "B.SilkS")
		)
		(fp_line
			(start 0.67945 0.3048)
			(end 0.67945 -0.305054)
			(stroke
				(width 0.1)
				(type default)
			)
			(layer "B.Fab")
		)
		(fp_line
			(start 0.67945 -0.305054)
			(end 0.12065 -0.305054)
			(stroke
				(width 0.1)
				(type default)
			)
			(layer "B.Fab")
		)
		(fp_line
			(start 0.12065 0.3048)
			(end 0.67945 0.3048)
			(stroke
				(width 0.1)
				(type default)
			)
			(layer "B.Fab")
		)
		(fp_line
			(start 0.12065 0.2794)
			(end 0.12065 0.3048)
			(stroke
				(width 0.1)
				(type default)
			)
			(layer "B.Fab")
		)
		(fp_line
			(start 0.12065 -0.2794)
			(end -0.12065 -0.2794)
			(stroke
				(width 0.1)
				(type default)
			)
			(layer "B.Fab")
		)
		(fp_line
			(start 0.12065 -0.305054)
			(end 0.12065 -0.2794)
			(stroke
				(width 0.1)
				(type default)
			)
			(layer "B.Fab")
		)
		(fp_line
			(start -0.120396 0.3048)
			(end -0.120396 0.2794)
			(stroke
				(width 0.1)
				(type default)
			)
			(layer "B.Fab")
		)
		(fp_line
			(start -0.120396 0.2794)
			(end 0.12065 0.2794)
			(stroke
				(width 0.1)
				(type default)
			)
			(layer "B.Fab")
		)
		(fp_line
			(start -0.12065 -0.2794)
			(end -0.12065 -0.3048)
			(stroke
				(width 0.1)
				(type default)
			)
			(layer "B.Fab")
		)
		(fp_line
			(start -0.12065 -0.3048)
			(end -0.67945 -0.3048)
			(stroke
				(width 0.1)
				(type default)
			)
			(layer "B.Fab")
		)
		(fp_line
			(start -0.67945 0.3048)
			(end -0.120396 0.3048)
			(stroke
				(width 0.1)
				(type default)
			)
			(layer "B.Fab")
		)
		(fp_line
			(start -0.67945 -0.3048)
			(end -0.67945 0.3048)
			(stroke
				(width 0.1)
				(type default)
			)
			(layer "B.Fab")
		)
		(pad "1" smd circle
			(at 0.40005 0)
			(size 0 0)
			(layers "B.Cu" "B.Mask" "B.Paste")
			(net "P3V3_9ZXL045_P1_VDD")
		)
		(pad "2" smd circle
			(at -0.40005 0)
			(size 0 0)
			(layers "B.Cu" "B.Mask" "B.Paste")
			(net "GND")
		)
	)
)
